FILE_TYPE = MACRO_DRAWING;
SET COLOR_WIRE YELLOW;
SET COLOR_PROP ORANGE;
SET COLOR_DOT WHITE;
SET COLOR_ARC YELLOW;
SET COLOR_BODY GREEN;
SET COLOR_NOTE PURPLE;
SET PROP_DISPLAY VALUE;
SET PAGE_NUMBER P116;
FORCEADD QUANTA_TITLE_BLOCK_C..1
(4875 -3600);
FORCEPROP 1 LAST Q_TITLE BLANK
J 0
(-4391 -3599);
DISPLAY 2.446809 (-4391 -3599);
PAINT GREEN (-4391 -3599);
FORCEPROP 2 LAST CUSTOM_TXT_CDS <CON_LAST_MODIFIED>
J 0
(2990 -3585);
DISPLAY 0.978723 (2990 -3585);
FORCEPROP 2 LAST CUSTOM_TXT_CDS <NAME_2>
J 0
(1700 -3550);
FORCEPROP 2 LAST CUSTOM_TXT_CDS <NAME_1>
J 0
(1700 -3425);
FORCEPROP 2 LAST CUSTOM_TXT_CDS <Q_NUMBER>
J 0
(3472 -3497);
DISPLAY 1.212766 (3472 -3497);
FORCEPROP 2 LAST CUSTOM_TXT_CDS <Q_PROJ>
J 0
(2493 -3498);
DISPLAY 1.212766 (2493 -3498);
FORCEPROP 2 LAST CUSTOM_TXT_CDS <Q_REV>
J 0
(4691 -3497);
DISPLAY 1.212766 (4691 -3497);
FORCEPROP 2 LAST CUSTOM_TXT_CDS <CON_PAGE_NUM> OF <CON_TOTAL_PAGES>
J 0
(4429 -3582);
DISPLAY 0.978723 (4429 -3582);
FORCEPROP 1 LAST Q_DEPT 
J 1
(1112 -3551);
DISPLAY 1.957447 (1112 -3551);
PAINT GREEN (1112 -3551);
FORCEPROP 2 LAST CDS_XR_PAGE_TITLE CR-116 : @S9S_MB_2U_LIB.S9S_MB_2U(SCH_1):PAGE116
J 0
(-3015 1650);
DISPLAY 0.638298 (-3015 1650);
PAINT PINK (-3015 1650);
DISPLAY INVISIBLE (-3015 1650);
FORCEPROP 2 LAST PAGE_BORDER TRUE
J 0
(-3015 1650);
DISPLAY 0.638298 (-3015 1650);
PAINT PINK (-3015 1650);
DISPLAY INVISIBLE (-3015 1650);
FORCEPROP 1 LAST CDS_LMAN_SYM_OUTLINE -9475,6775,100,-125
J 0
(4875 -3600);
DISPLAY 0.468085 (4875 -3600);
PAINT GREEN (4875 -3600);
DISPLAY INVISIBLE (4875 -3600);
FORCEPROP 2 LAST CDS_LIB pure_quanta
J 0
(4875 -3600);
PAINT MONO (4875 -3600);
DISPLAY INVISIBLE (4875 -3600);
FORCEPROP 1 LAST COMMENT_BODY TRUE
J 0
(4887 -3613);
DISPLAY 0.978723 (4887 -3613);
PAINT GREEN (4887 -3613);
DISPLAY INVISIBLE (4887 -3613);
FORCEPROP 2 LAST CUSTOM_TXT_CDS <XR_PAGE_TITLE>
J 0
(-3015 1650);
DISPLAY 0.638298 (-3015 1650);
PAINT PINK (-3015 1650);
DISPLAY INVISIBLE (-3015 1650);
FORCEPROP 0 LAST CDS_CON_LAST_MODIFIED Thu Aug 24 16:13:36 2023
J 0
(2990 -3585);
PAINT MONO (2990 -3585);
DISPLAY INVISIBLE (2990 -3585);
FORCENOTE
THIS PAGE WAS INTENTIONALLY LEFT BLANK
(-4100 -150) 0;
DISPLAY LEFT (-4100 -150);
DISPLAY 4.914894 (-4100 -150);
QUIT
